# T6G (Grand Teton) — schematic netlist excerpt (pin names and nets, part order shuffled) for the footprints in the layout excerpt that follows; sources: Cadence DE-HDL packaged netlist, KiCad conversion of 04192023_DAF0TMB3IC0_F0TG_MB_C_brd_V02_OCP.brd

C687  Q_CAP_DIFFBUS  DIFF BUS_0.22UF 6.3V 20% X6S  pkg C0201  page 67 : \1\ = P5E_CPU1_G1_TX_C_DP<11> ; \2\ = P5E_CPU1_G1_TX_DP<11>
PR347  Q_RES  8.87K 1% EMPTY  pkg 0402LF  page 195 : A = GND ; B = PVDDCR_CPU0_P0_LSET4
R4901  Q_RES  82K 1% CHIP  pkg 0402LF  page 268 : A = P12V_PSU_FUSE ; B = HSC_EN

(kicad_pcb
	(version 20260206)
	(generator "pcbnew")
	(generator_version "10.0")
	(general
		(thickness 1.6)
		(legacy_teardrops no)
	)
	(paper "A4")
	(title_block
		(title "04192023_DAF0TMB3IC0_F0TG_MB_C_brd_V02_OCP.brd")
		(comment 1 "Grand Teton / footprints 2280-2282 of 8354")
	)
	(layers
		(0 "F.Cu" signal "TOP")
		(4 "In1.Cu" signal "GND")
		(6 "In2.Cu" signal "IN1")
		(8 "In3.Cu" signal "GND1")
		(10 "In4.Cu" signal "IN2")
		(12 "In5.Cu" signal "GND2")
		(14 "In6.Cu" signal "IN3")
		(16 "In7.Cu" signal "GND3")
		(18 "In8.Cu" signal "VCC")
		(20 "In9.Cu" signal "VCC1")
		(22 "In10.Cu" signal "GND4")
		(24 "In11.Cu" signal "IN4")
		(26 "In12.Cu" signal "GND5")
		(28 "In13.Cu" signal "IN5")
		(30 "In14.Cu" signal "GND6")
		(32 "In15.Cu" signal "IN6")
		(34 "In16.Cu" signal "GND7")
		(2 "B.Cu" signal "BOTTOM")
		(9 "F.Adhes" user "F.Adhesive")
		(11 "B.Adhes" user "B.Adhesive")
		(13 "F.Paste" user "Package Geometry/Pastemask Top")
		(15 "B.Paste" user "Package Geometry/Pastemask Bottom")
		(5 "F.SilkS" user "Ref Des/Silkscreen Top")
		(7 "B.SilkS" user "Ref Des/Silkscreen Bottom")
		(1 "F.Mask" user "Board Geometry/Soldermask Top")
		(3 "B.Mask" user "Board Geometry/Soldermask Bottom")
		(17 "Dwgs.User" user "User.Drawings")
		(19 "Cmts.User" user "User.Comments")
		(21 "Eco1.User" user "User.Eco1")
		(23 "Eco2.User" user "User.Eco2")
		(25 "Edge.Cuts" user "Board Geometry/Outline")
		(27 "Margin" user)
		(31 "F.CrtYd" user "Package Geometry/Place Bound Top")
		(29 "B.CrtYd" user "Package Geometry/Place Bound Bottom")
		(35 "F.Fab" user "Ref Des/Assembly Top")
		(33 "B.Fab" user "Ref Des/Assembly Bottom")
	)
	(footprint ""
		(layer "F.Cu")
		(at 390.713722 -177.532284)
		(property "Reference" "PR347"
			(at 0 0 0)
			(layer "F.SilkS")
			(hide yes)
			(effects
				(font
					(size 1.27 1.27)
				)
			)
		)
		(property "Value" ""
			(at 0 0 0)
			(layer "F.Fab")
			(effects
				(font
					(size 1.27 1.27)
				)
			)
		)
		(duplicate_pad_numbers_are_jumpers no)
		(fp_line
			(start -0.7874 -0.4064)
			(end 0.7874 -0.4064)
			(stroke
				(width 0.1524)
				(type default)
			)
			(layer "F.SilkS")
		)
		(fp_line
			(start -0.7874 0.4064)
			(end -0.7874 -0.4064)
			(stroke
				(width 0.1524)
				(type default)
			)
			(layer "F.SilkS")
		)
		(fp_line
			(start 0.7874 -0.4064)
			(end 0.7874 0.4064)
			(stroke
				(width 0.1524)
				(type default)
			)
			(layer "F.SilkS")
		)
		(fp_line
			(start 0.7874 0.4064)
			(end -0.7874 0.4064)
			(stroke
				(width 0.1524)
				(type default)
			)
			(layer "F.SilkS")
		)
		(fp_line
			(start -0.67945 -0.305054)
			(end -0.12065 -0.305054)
			(stroke
				(width 0.1)
				(type default)
			)
			(layer "F.Fab")
		)
		(fp_line
			(start -0.67945 0.3048)
			(end -0.67945 -0.305054)
			(stroke
				(width 0.1)
				(type default)
			)
			(layer "F.Fab")
		)
		(fp_line
			(start -0.12065 -0.305054)
			(end -0.12065 -0.2794)
			(stroke
				(width 0.1)
				(type default)
			)
			(layer "F.Fab")
		)
		(fp_line
			(start -0.12065 -0.2794)
			(end 0.12065 -0.2794)
			(stroke
				(width 0.1)
				(type default)
			)
			(layer "F.Fab")
		)
		(fp_line
			(start -0.12065 0.2794)
			(end -0.12065 0.3048)
			(stroke
				(width 0.1)
				(type default)
			)
			(layer "F.Fab")
		)
		(fp_line
			(start -0.12065 0.3048)
			(end -0.67945 0.3048)
			(stroke
				(width 0.1)
				(type default)
			)
			(layer "F.Fab")
		)
		(fp_line
			(start 0.120396 0.2794)
			(end -0.12065 0.2794)
			(stroke
				(width 0.1)
				(type default)
			)
			(layer "F.Fab")
		)
		(fp_line
			(start 0.120396 0.3048)
			(end 0.120396 0.2794)
			(stroke
				(width 0.1)
				(type default)
			)
			(layer "F.Fab")
		)
		(fp_line
			(start 0.12065 -0.3048)
			(end 0.67945 -0.3048)
			(stroke
				(width 0.1)
				(type default)
			)
			(layer "F.Fab")
		)
		(fp_line
			(start 0.12065 -0.2794)
			(end 0.12065 -0.3048)
			(stroke
				(width 0.1)
				(type default)
			)
			(layer "F.Fab")
		)
		(fp_line
			(start 0.67945 -0.3048)
			(end 0.67945 0.3048)
			(stroke
				(width 0.1)
				(type default)
			)
			(layer "F.Fab")
		)
		(fp_line
			(start 0.67945 0.3048)
			(end 0.120396 0.3048)
			(stroke
				(width 0.1)
				(type default)
			)
			(layer "F.Fab")
		)
		(pad "1" smd circle
			(at -0.40005 0)
			(size 0 0)
			(layers "F.Cu" "F.Mask" "F.Paste")
			(net "GND")
		)
		(pad "2" smd circle
			(at 0.40005 0)
			(size 0 0)
			(layers "F.Cu" "F.Mask" "F.Paste")
			(net "PVDDCR_CPU0_P0_LSET4")
		)
	)
	(footprint ""
		(layer "F.Cu")
		(at 27.598878 -16.099536 90)
		(property "Reference" "C687"
			(at 0 0 90)
			(layer "F.SilkS")
			(hide yes)
			(effects
				(font
					(size 1.27 1.27)
				)
			)
		)
		(property "Value" ""
			(at 0 0 90)
			(layer "F.Fab")
			(effects
				(font
					(size 1.27 1.27)
				)
			)
		)
		(duplicate_pad_numbers_are_jumpers no)
		(fp_line
			(start 0.299974 -0.150114)
			(end 0.299974 0.150114)
			(stroke
				(width 0.1)
				(type default)
			)
			(layer "F.Fab")
		)
		(fp_line
			(start -0.299974 -0.150114)
			(end 0.299974 -0.150114)
			(stroke
				(width 0.1)
				(type default)
			)
			(layer "F.Fab")
		)
		(fp_line
			(start 0.299974 0.150114)
			(end -0.299974 0.150114)
			(stroke
				(width 0.1)
				(type default)
			)
			(layer "F.Fab")
		)
		(fp_line
			(start -0.299974 0.150114)
			(end -0.299974 -0.150114)
			(stroke
				(width 0.1)
				(type default)
			)
			(layer "F.Fab")
		)
		(pad "1" smd rect
			(at -0.2667 0 90)
			(size 0.3048 0.381)
			(layers "F.Cu" "F.Mask" "F.Paste")
			(net "P5E_CPU1_G1_TX_C_DP<11>")
		)
		(pad "2" smd rect
			(at 0.2667 0 90)
			(size 0.3048 0.381)
			(layers "F.Cu" "F.Mask" "F.Paste")
			(net "P5E_CPU1_G1_TX_DP<11>")
		)
	)
	(footprint ""
		(layer "F.Cu")
		(at 265.201908 -418.13607)
		(property "Reference" "R4901"
			(at 0 0 0)
			(layer "F.SilkS")
			(hide yes)
			(effects
				(font
					(size 1.27 1.27)
				)
			)
		)
		(property "Value" ""
			(at 0 0 0)
			(layer "F.Fab")
			(effects
				(font
					(size 1.27 1.27)
				)
			)
		)
		(duplicate_pad_numbers_are_jumpers no)
		(fp_line
			(start -0.7874 -0.4064)
			(end 0.7874 -0.4064)
			(stroke
				(width 0.1524)
				(type default)
			)
			(layer "F.SilkS")
		)
		(fp_line
			(start -0.7874 0.4064)
			(end -0.7874 -0.4064)
			(stroke
				(width 0.1524)
				(type default)
			)
			(layer "F.SilkS")
		)
		(fp_line
			(start 0.7874 -0.4064)
			(end 0.7874 0.4064)
			(stroke
				(width 0.1524)
				(type default)
			)
			(layer "F.SilkS")
		)
		(fp_line
			(start 0.7874 0.4064)
			(end -0.7874 0.4064)
			(stroke
				(width 0.1524)
				(type default)
			)
			(layer "F.SilkS")
		)
		(fp_line
			(start -0.67945 -0.305054)
			(end -0.12065 -0.305054)
			(stroke
				(width 0.1)
				(type default)
			)
			(layer "F.Fab")
		)
		(fp_line
			(start -0.67945 0.3048)
			(end -0.67945 -0.305054)
			(stroke
				(width 0.1)
				(type default)
			)
			(layer "F.Fab")
		)
		(fp_line
			(start -0.12065 -0.305054)
			(end -0.12065 -0.2794)
			(stroke
				(width 0.1)
				(type default)
			)
			(layer "F.Fab")
		)
		(fp_line
			(start -0.12065 -0.2794)
			(end 0.12065 -0.2794)
			(stroke
				(width 0.1)
				(type default)
			)
			(layer "F.Fab")
		)
		(fp_line
			(start -0.12065 0.2794)
			(end -0.12065 0.3048)
			(stroke
				(width 0.1)
				(type default)
			)
			(layer "F.Fab")
		)
		(fp_line
			(start -0.12065 0.3048)
			(end -0.67945 0.3048)
			(stroke
				(width 0.1)
				(type default)
			)
			(layer "F.Fab")
		)
		(fp_line
			(start 0.120396 0.2794)
			(end -0.12065 0.2794)
			(stroke
				(width 0.1)
				(type default)
			)
			(layer "F.Fab")
		)
		(fp_line
			(start 0.120396 0.3048)
			(end 0.120396 0.2794)
			(stroke
				(width 0.1)
				(type default)
			)
			(layer "F.Fab")
		)
		(fp_line
			(start 0.12065 -0.3048)
			(end 0.67945 -0.3048)
			(stroke
				(width 0.1)
				(type default)
			)
			(layer "F.Fab")
		)
		(fp_line
			(start 0.12065 -0.2794)
			(end 0.12065 -0.3048)
			(stroke
				(width 0.1)
				(type default)
			)
			(layer "F.Fab")
		)
		(fp_line
			(start 0.67945 -0.3048)
			(end 0.67945 0.3048)
			(stroke
				(width 0.1)
				(type default)
			)
			(layer "F.Fab")
		)
		(fp_line
			(start 0.67945 0.3048)
			(end 0.120396 0.3048)
			(stroke
				(width 0.1)
				(type default)
			)
			(layer "F.Fab")
		)
		(pad "1" smd circle
			(at -0.40005 0)
			(size 0 0)
			(layers "F.Cu" "F.Mask" "F.Paste")
			(net "P12V_PSU_FUSE")
		)
		(pad "2" smd circle
			(at 0.40005 0)
			(size 0 0)
			(layers "F.Cu" "F.Mask" "F.Paste")
			(net "HSC_EN")
		)
	)
)
